# ZAIUS-MB-PVT-X04-BOM_X31_20180131_Final.xls.xlsx — TBD AVL Qual (bom)
| NOTES: |  |  |  |  |  |  |
| The following items are alternates to the items listed in the Critical Components Qual tab. |  |  |  |  |  |  |
| These components will be included on near future, non-customer builds for validation and approval by both Customer and the ODM. |  |  |  |  |  |  |
| Item Description | ODM P/N | Customer PN | Vendor | Vendor PN | Build ?? | Estimated Completion Date |
| SATA connectors (black) |  |  |  |  |  |  |
| -  Alternate |  |  |  |  |  |  |
| SATA connectors (blue) |  |  |  |  |  |  |
| -  Alternate |  |  |  |  |  |  |
| PCIe retention |  |  |  |  |  |  |
| -  Alternate |  |  |  |  |  |  |
| RTC XTAL |  |  |  |  |  |  |
| -  Alternate |  |  |  |  |  |  |
| XTAL |  |  |  |  |  |  |
| -  Alternate |  |  |  |  |  |  |
